# S9S_MB_2U (Grand Teton) — schematic netlist excerpt (pin names and nets, part order shuffled) for the footprints in the layout excerpt that follows; sources: Cadence DE-HDL packaged netlist, KiCad conversion of 03242023_DA0F0TMBIJ0_F0T_Motherboard_J_brd_V01_OCP.brd

PR3336  Q_RES  30.1K 1% CHIP  pkg 0402LF  page 299 : A = PVPP_HBM_CPU1_MODE ; B = GND
PC1270  Q_CAP  22UF 4V 20% X6S  pkg C0805  page 299 : A = PVPP_HBM_CPU1 ; B = GND
R4285  Q_RES  1K 1% EMPTY  pkg 0402LF  page 169 : A = FM_USB3_1_SWB ; B = GND

(kicad_pcb
	(version 20260206)
	(generator "pcbnew")
	(generator_version "10.0")
	(general
		(thickness 1.6)
		(legacy_teardrops no)
	)
	(paper "A4")
	(title_block
		(title "03242023_DA0F0TMBIJ0_F0T_Motherboard_J_brd_V01_OCP.brd")
		(comment 1 "Grand Teton / footprints 5659-5661 of 6105")
	)
	(layers
		(0 "F.Cu" signal "TOP")
		(4 "In1.Cu" signal "GND")
		(6 "In2.Cu" signal "IN1")
		(8 "In3.Cu" signal "GND1")
		(10 "In4.Cu" signal "IN2")
		(12 "In5.Cu" signal "GND2")
		(14 "In6.Cu" signal "IN3")
		(16 "In7.Cu" signal "GND3")
		(18 "In8.Cu" signal "VCC")
		(20 "In9.Cu" signal "VCC1")
		(22 "In10.Cu" signal "GND4")
		(24 "In11.Cu" signal "IN4")
		(26 "In12.Cu" signal "GND5")
		(28 "In13.Cu" signal "IN5")
		(30 "In14.Cu" signal "GND6")
		(32 "In15.Cu" signal "IN6")
		(34 "In16.Cu" signal "GND7")
		(2 "B.Cu" signal "BOTTOM")
		(9 "F.Adhes" user "F.Adhesive")
		(11 "B.Adhes" user "B.Adhesive")
		(13 "F.Paste" user "Package Geometry/Pastemask Top")
		(15 "B.Paste" user "Package Geometry/Pastemask Bottom")
		(5 "F.SilkS" user "Ref Des/Silkscreen Top")
		(7 "B.SilkS" user "Ref Des/Silkscreen Bottom")
		(1 "F.Mask" user "Board Geometry/Soldermask Top")
		(3 "B.Mask" user "Board Geometry/Soldermask Bottom")
		(17 "Dwgs.User" user "User.Drawings")
		(19 "Cmts.User" user "User.Comments")
		(21 "Eco1.User" user "User.Eco1")
		(23 "Eco2.User" user "User.Eco2")
		(25 "Edge.Cuts" user "Board Geometry/Outline")
		(27 "Margin" user)
		(31 "F.CrtYd" user "Package Geometry/Place Bound Top")
		(29 "B.CrtYd" user "Package Geometry/Place Bound Bottom")
		(35 "F.Fab" user "Ref Des/Assembly Top")
		(33 "B.Fab" user "Ref Des/Assembly Bottom")
	)
	(footprint ""
		(layer "B.Cu")
		(at 125.773942 -366.723168 90)
		(property "Reference" "PC1270"
			(at 0 0 90)
			(layer "B.SilkS")
			(hide yes)
			(effects
				(font
					(size 1.27 1.27)
				)
				(justify mirror)
			)
		)
		(property "Value" ""
			(at 0 0 90)
			(layer "B.Fab")
			(effects
				(font
					(size 1.27 1.27)
				)
				(justify mirror)
			)
		)
		(duplicate_pad_numbers_are_jumpers no)
		(fp_line
			(start 1.524 -0.762)
			(end -1.524 -0.762)
			(stroke
				(width 0.1524)
				(type default)
			)
			(layer "B.SilkS")
		)
		(fp_line
			(start -1.524 -0.762)
			(end -1.524 0.762)
			(stroke
				(width 0.1524)
				(type default)
			)
			(layer "B.SilkS")
		)
		(fp_line
			(start 1.524 0.762)
			(end 1.524 -0.762)
			(stroke
				(width 0.1524)
				(type default)
			)
			(layer "B.SilkS")
		)
		(fp_line
			(start -1.524 0.762)
			(end 1.524 0.762)
			(stroke
				(width 0.1524)
				(type default)
			)
			(layer "B.SilkS")
		)
		(fp_line
			(start 1.1049 -0.724916)
			(end 1.1049 0.724916)
			(stroke
				(width 0.1)
				(type default)
			)
			(layer "B.Fab")
		)
		(fp_line
			(start -1.1049 -0.724916)
			(end 1.1049 -0.724916)
			(stroke
				(width 0.1)
				(type default)
			)
			(layer "B.Fab")
		)
		(fp_line
			(start 1.1049 0.724916)
			(end -1.1049 0.724916)
			(stroke
				(width 0.1)
				(type default)
			)
			(layer "B.Fab")
		)
		(fp_line
			(start -1.1049 0.724916)
			(end -1.1049 -0.724916)
			(stroke
				(width 0.1)
				(type default)
			)
			(layer "B.Fab")
		)
		(pad "1" smd rect
			(at 0.889 0 90)
			(size 1.016 1.27)
			(layers "B.Cu" "B.Mask" "B.Paste")
			(net "PVPP_HBM_CPU1")
		)
		(pad "2" smd rect
			(at -0.889 0 90)
			(size 1.016 1.27)
			(layers "B.Cu" "B.Mask" "B.Paste")
			(net "GND")
		)
	)
	(footprint ""
		(layer "B.Cu")
		(at 124.09678 -359.364534 -90)
		(property "Reference" "PR3336"
			(at 0 0 90)
			(layer "B.SilkS")
			(hide yes)
			(effects
				(font
					(size 1.27 1.27)
				)
				(justify mirror)
			)
		)
		(property "Value" ""
			(at 0 0 90)
			(layer "B.Fab")
			(effects
				(font
					(size 1.27 1.27)
				)
				(justify mirror)
			)
		)
		(duplicate_pad_numbers_are_jumpers no)
		(fp_line
			(start -0.7874 0.4064)
			(end 0.7874 0.4064)
			(stroke
				(width 0.1524)
				(type default)
			)
			(layer "B.SilkS")
		)
		(fp_line
			(start 0.7874 0.4064)
			(end 0.7874 -0.4064)
			(stroke
				(width 0.1524)
				(type default)
			)
			(layer "B.SilkS")
		)
		(fp_line
			(start -0.7874 -0.4064)
			(end -0.7874 0.4064)
			(stroke
				(width 0.1524)
				(type default)
			)
			(layer "B.SilkS")
		)
		(fp_line
			(start 0.7874 -0.4064)
			(end -0.7874 -0.4064)
			(stroke
				(width 0.1524)
				(type default)
			)
			(layer "B.SilkS")
		)
		(fp_line
			(start -0.67945 0.3048)
			(end -0.120396 0.3048)
			(stroke
				(width 0.1)
				(type default)
			)
			(layer "B.Fab")
		)
		(fp_line
			(start -0.120396 0.3048)
			(end -0.120396 0.2794)
			(stroke
				(width 0.1)
				(type default)
			)
			(layer "B.Fab")
		)
		(fp_line
			(start 0.12065 0.3048)
			(end 0.67945 0.3048)
			(stroke
				(width 0.1)
				(type default)
			)
			(layer "B.Fab")
		)
		(fp_line
			(start 0.67945 0.3048)
			(end 0.67945 -0.305054)
			(stroke
				(width 0.1)
				(type default)
			)
			(layer "B.Fab")
		)
		(fp_line
			(start -0.120396 0.2794)
			(end 0.12065 0.2794)
			(stroke
				(width 0.1)
				(type default)
			)
			(layer "B.Fab")
		)
		(fp_line
			(start 0.12065 0.2794)
			(end 0.12065 0.3048)
			(stroke
				(width 0.1)
				(type default)
			)
			(layer "B.Fab")
		)
		(fp_line
			(start -0.12065 -0.2794)
			(end -0.12065 -0.3048)
			(stroke
				(width 0.1)
				(type default)
			)
			(layer "B.Fab")
		)
		(fp_line
			(start 0.12065 -0.2794)
			(end -0.12065 -0.2794)
			(stroke
				(width 0.1)
				(type default)
			)
			(layer "B.Fab")
		)
		(fp_line
			(start -0.67945 -0.3048)
			(end -0.67945 0.3048)
			(stroke
				(width 0.1)
				(type default)
			)
			(layer "B.Fab")
		)
		(fp_line
			(start -0.12065 -0.3048)
			(end -0.67945 -0.3048)
			(stroke
				(width 0.1)
				(type default)
			)
			(layer "B.Fab")
		)
		(fp_line
			(start 0.12065 -0.305054)
			(end 0.12065 -0.2794)
			(stroke
				(width 0.1)
				(type default)
			)
			(layer "B.Fab")
		)
		(fp_line
			(start 0.67945 -0.305054)
			(end 0.12065 -0.305054)
			(stroke
				(width 0.1)
				(type default)
			)
			(layer "B.Fab")
		)
		(pad "1" smd circle
			(at 0.40005 0 90)
			(size 0 0)
			(layers "B.Cu" "B.Mask" "B.Paste")
			(net "PVPP_HBM_CPU1_MODE")
		)
		(pad "2" smd circle
			(at -0.40005 0 90)
			(size 0 0)
			(layers "B.Cu" "B.Mask" "B.Paste")
			(net "GND")
		)
	)
	(footprint ""
		(layer "B.Cu")
		(at 127.83566 -36.759388 90)
		(property "Reference" "R4285"
			(at 0 0 90)
			(layer "B.SilkS")
			(hide yes)
			(effects
				(font
					(size 1.27 1.27)
				)
				(justify mirror)
			)
		)
		(property "Value" ""
			(at 0 0 90)
			(layer "B.Fab")
			(effects
				(font
					(size 1.27 1.27)
				)
				(justify mirror)
			)
		)
		(duplicate_pad_numbers_are_jumpers no)
		(fp_line
			(start 0.7874 -0.4064)
			(end -0.7874 -0.4064)
			(stroke
				(width 0.1524)
				(type default)
			)
			(layer "B.SilkS")
		)
		(fp_line
			(start -0.7874 -0.4064)
			(end -0.7874 0.4064)
			(stroke
				(width 0.1524)
				(type default)
			)
			(layer "B.SilkS")
		)
		(fp_line
			(start 0.7874 0.4064)
			(end 0.7874 -0.4064)
			(stroke
				(width 0.1524)
				(type default)
			)
			(layer "B.SilkS")
		)
		(fp_line
			(start -0.7874 0.4064)
			(end 0.7874 0.4064)
			(stroke
				(width 0.1524)
				(type default)
			)
			(layer "B.SilkS")
		)
		(fp_line
			(start 0.67945 -0.305054)
			(end 0.12065 -0.305054)
			(stroke
				(width 0.1)
				(type default)
			)
			(layer "B.Fab")
		)
		(fp_line
			(start 0.12065 -0.305054)
			(end 0.12065 -0.2794)
			(stroke
				(width 0.1)
				(type default)
			)
			(layer "B.Fab")
		)
		(fp_line
			(start -0.12065 -0.3048)
			(end -0.67945 -0.3048)
			(stroke
				(width 0.1)
				(type default)
			)
			(layer "B.Fab")
		)
		(fp_line
			(start -0.67945 -0.3048)
			(end -0.67945 0.3048)
			(stroke
				(width 0.1)
				(type default)
			)
			(layer "B.Fab")
		)
		(fp_line
			(start 0.12065 -0.2794)
			(end -0.12065 -0.2794)
			(stroke
				(width 0.1)
				(type default)
			)
			(layer "B.Fab")
		)
		(fp_line
			(start -0.12065 -0.2794)
			(end -0.12065 -0.3048)
			(stroke
				(width 0.1)
				(type default)
			)
			(layer "B.Fab")
		)
		(fp_line
			(start 0.12065 0.2794)
			(end 0.12065 0.3048)
			(stroke
				(width 0.1)
				(type default)
			)
			(layer "B.Fab")
		)
		(fp_line
			(start -0.120396 0.2794)
			(end 0.12065 0.2794)
			(stroke
				(width 0.1)
				(type default)
			)
			(layer "B.Fab")
		)
		(fp_line
			(start 0.67945 0.3048)
			(end 0.67945 -0.305054)
			(stroke
				(width 0.1)
				(type default)
			)
			(layer "B.Fab")
		)
		(fp_line
			(start 0.12065 0.3048)
			(end 0.67945 0.3048)
			(stroke
				(width 0.1)
				(type default)
			)
			(layer "B.Fab")
		)
		(fp_line
			(start -0.120396 0.3048)
			(end -0.120396 0.2794)
			(stroke
				(width 0.1)
				(type default)
			)
			(layer "B.Fab")
		)
		(fp_line
			(start -0.67945 0.3048)
			(end -0.120396 0.3048)
			(stroke
				(width 0.1)
				(type default)
			)
			(layer "B.Fab")
		)
		(pad "1" smd circle
			(at 0.40005 0 270)
			(size 0 0)
			(layers "B.Cu" "B.Mask" "B.Paste")
			(net "FM_USB3_1_SWB")
		)
		(pad "2" smd circle
			(at -0.40005 0 270)
			(size 0 0)
			(layers "B.Cu" "B.Mask" "B.Paste")
			(net "GND")
		)
	)
)
